# BASEBOARD_FAB2 (Tioga Pass) — schematic netlist excerpt (pin names and nets, part order shuffled) for the footprints in the layout excerpt that follows; sources: Cadence DE-HDL packaged netlist, KiCad conversion of Wiwynn_Tioga_Pass_MB.brd

C3B6  CAPP  68UF 16V 20% TANT  pkg 3018  page 195 : A = P12V_STBY ; B = GND
C4D33  CAP  1000PF 50V 10% X7R  pkg 0402LF  page 213 : A = PWRGD_PVCCIO_CPU1_R ; B = GND
C9A2  CAP_A  0.1UF 16V 10% X7R  pkg 0402V  page 111 : A = XDP_SYSPWROK ; B = GND

(kicad_pcb
	(version 20260206)
	(generator "pcbnew")
	(generator_version "10.0")
	(general
		(thickness 1.6)
		(legacy_teardrops no)
	)
	(paper "A4")
	(title_block
		(title "Wiwynn_Tioga_Pass_MB.brd")
		(comment 1 "Tioga Pass / footprints 2245-2247 of 4770")
	)
	(layers
		(0 "F.Cu" signal "TOP")
		(4 "In1.Cu" signal "L2GND")
		(6 "In2.Cu" signal "L3")
		(8 "In3.Cu" signal "L4GND")
		(10 "In4.Cu" signal "L5")
		(12 "In5.Cu" signal "L6GND")
		(14 "In6.Cu" signal "L7VCC")
		(16 "In7.Cu" signal "L8VCC")
		(18 "In8.Cu" signal "L9GND")
		(20 "In9.Cu" signal "L10")
		(22 "In10.Cu" signal "L11GND")
		(24 "In11.Cu" signal "L12")
		(26 "In12.Cu" signal "L13GND")
		(2 "B.Cu" signal "BOTTOM")
		(9 "F.Adhes" user "F.Adhesive")
		(11 "B.Adhes" user "B.Adhesive")
		(13 "F.Paste" user "Package Geometry/Pastemask Top")
		(15 "B.Paste" user "Package Geometry/Pastemask Bottom")
		(5 "F.SilkS" user "Ref Des/Silkscreen Top")
		(7 "B.SilkS" user "Ref Des/Silkscreen Bottom")
		(1 "F.Mask" user "Board Geometry/Soldermask Top")
		(3 "B.Mask" user "Board Geometry/Soldermask Bottom")
		(17 "Dwgs.User" user "User.Drawings")
		(19 "Cmts.User" user "User.Comments")
		(21 "Eco1.User" user "User.Eco1")
		(23 "Eco2.User" user "User.Eco2")
		(25 "Edge.Cuts" user "Board Geometry/Outline")
		(27 "Margin" user)
		(31 "F.CrtYd" user "Package Geometry/Place Bound Top")
		(29 "B.CrtYd" user "Package Geometry/Place Bound Bottom")
		(35 "F.Fab" user "Ref Des/Assembly Top")
		(33 "B.Fab" user "Ref Des/Assembly Bottom")
	)
	(footprint ""
		(layer "F.Cu")
		(at 466.09 -148.0185 180)
		(property "Reference" "C9A2"
			(at 0 0 180)
			(layer "F.SilkS")
			(hide yes)
			(effects
				(font
					(size 1.27 1.27)
				)
			)
		)
		(property "Value" ""
			(at 0 0 180)
			(layer "F.Fab")
			(effects
				(font
					(size 1.27 1.27)
				)
			)
		)
		(duplicate_pad_numbers_are_jumpers no)
		(fp_poly
			(pts
				(xy 0.3048 -0.1016) (xy 0.3048 0.9906) (xy -0.3048 0.9906) (xy -0.3048 -0.1016)
			)
			(stroke
				(width 0)
				(type default)
			)
			(fill no)
			(layer "F.CrtYd")
		)
		(fp_line
			(start 0.3048 0.9906)
			(end 0.3048 -0.1016)
			(stroke
				(width 0.1)
				(type default)
			)
			(layer "F.Fab")
		)
		(fp_line
			(start 0.3048 -0.1016)
			(end -0.3048 -0.1016)
			(stroke
				(width 0.1)
				(type default)
			)
			(layer "F.Fab")
		)
		(fp_line
			(start -0.3048 0.9906)
			(end 0.3048 0.9906)
			(stroke
				(width 0.1)
				(type default)
			)
			(layer "F.Fab")
		)
		(fp_line
			(start -0.3048 -0.1016)
			(end -0.3048 0.9906)
			(stroke
				(width 0.1)
				(type default)
			)
			(layer "F.Fab")
		)
		(pad "1" smd rect
			(at 0 0 180)
			(size 0.508 0.508)
			(layers "F.Cu" "F.Mask" "F.Paste")
			(net "XDP_SYSPWROK")
		)
		(pad "2" smd rect
			(at 0 0.889 180)
			(size 0.508 0.508)
			(layers "F.Cu" "F.Mask" "F.Paste")
			(net "GND")
		)
		(zone
			(layer "F.Cu")
			(hatch none 0.5)
			(connect_pads
				(clearance 0)
			)
			(min_thickness 0.25)
			(keepout
				(tracks not_allowed)
				(vias allowed)
				(pads allowed)
				(copperpour not_allowed)
				(footprints allowed)
			)
			(placement
				(enabled no)
				(sheetname "")
			)
			(fill
				(thermal_gap 0.5)
				(thermal_bridge_width 0.5)
				(island_removal_mode 0)
			)
			(polygon
				(pts
					(xy 466.344 -148.6535) (xy 465.836 -148.6535) (xy 465.836 -148.2725) (xy 466.344 -148.2725)
				)
			)
		)
		(zone
			(layer "F.Cu")
			(hatch none 0.5)
			(connect_pads
				(clearance 0)
			)
			(min_thickness 0.25)
			(keepout
				(tracks allowed)
				(vias not_allowed)
				(pads allowed)
				(copperpour not_allowed)
				(footprints allowed)
			)
			(placement
				(enabled no)
				(sheetname "")
			)
			(fill
				(thermal_gap 0.5)
				(thermal_bridge_width 0.5)
				(island_removal_mode 0)
			)
			(polygon
				(pts
					(xy 466.344 -148.2725) (xy 465.836 -148.2725) (xy 465.836 -148.6535) (xy 466.344 -148.6535)
				)
			)
		)
	)
	(footprint ""
		(layer "F.Cu")
		(at 165.481 -70.6374 180)
		(property "Reference" "C4D33"
			(at 0 0 180)
			(layer "F.SilkS")
			(hide yes)
			(effects
				(font
					(size 1.27 1.27)
				)
			)
		)
		(property "Value" ""
			(at 0 0 180)
			(layer "F.Fab")
			(effects
				(font
					(size 1.27 1.27)
				)
			)
		)
		(duplicate_pad_numbers_are_jumpers no)
		(fp_poly
			(pts
				(xy 0.3048 -0.1016) (xy 0.3048 0.9906) (xy -0.3048 0.9906) (xy -0.3048 -0.1016)
			)
			(stroke
				(width 0)
				(type default)
			)
			(fill no)
			(layer "F.CrtYd")
		)
		(fp_line
			(start 0.3048 0.9906)
			(end 0.3048 -0.1016)
			(stroke
				(width 0.1)
				(type default)
			)
			(layer "F.Fab")
		)
		(fp_line
			(start 0.3048 -0.1016)
			(end -0.3048 -0.1016)
			(stroke
				(width 0.1)
				(type default)
			)
			(layer "F.Fab")
		)
		(fp_line
			(start -0.3048 0.9906)
			(end 0.3048 0.9906)
			(stroke
				(width 0.1)
				(type default)
			)
			(layer "F.Fab")
		)
		(fp_line
			(start -0.3048 -0.1016)
			(end -0.3048 0.9906)
			(stroke
				(width 0.1)
				(type default)
			)
			(layer "F.Fab")
		)
		(pad "1" smd rect
			(at 0 0 180)
			(size 0.508 0.508)
			(layers "F.Cu" "F.Mask" "F.Paste")
			(net "PWRGD_PVCCIO_CPU1_R")
		)
		(pad "2" smd rect
			(at 0 0.889 180)
			(size 0.508 0.508)
			(layers "F.Cu" "F.Mask" "F.Paste")
			(net "GND")
		)
		(zone
			(layer "F.Cu")
			(hatch none 0.5)
			(connect_pads
				(clearance 0)
			)
			(min_thickness 0.25)
			(keepout
				(tracks not_allowed)
				(vias allowed)
				(pads allowed)
				(copperpour not_allowed)
				(footprints allowed)
			)
			(placement
				(enabled no)
				(sheetname "")
			)
			(fill
				(thermal_gap 0.5)
				(thermal_bridge_width 0.5)
				(island_removal_mode 0)
			)
			(polygon
				(pts
					(xy 165.735 -71.2724) (xy 165.227 -71.2724) (xy 165.227 -70.8914) (xy 165.735 -70.8914)
				)
			)
		)
		(zone
			(layer "F.Cu")
			(hatch none 0.5)
			(connect_pads
				(clearance 0)
			)
			(min_thickness 0.25)
			(keepout
				(tracks allowed)
				(vias not_allowed)
				(pads allowed)
				(copperpour not_allowed)
				(footprints allowed)
			)
			(placement
				(enabled no)
				(sheetname "")
			)
			(fill
				(thermal_gap 0.5)
				(thermal_bridge_width 0.5)
				(island_removal_mode 0)
			)
			(polygon
				(pts
					(xy 165.735 -70.8914) (xy 165.227 -70.8914) (xy 165.227 -71.2724) (xy 165.735 -71.2724)
				)
			)
		)
	)
	(footprint ""
		(layer "F.Cu")
		(at 151.892 -120.142 -90)
		(property "Reference" "C3B6"
			(at 3.20167 3.81 0)
			(unlocked yes)
			(layer "F.SilkS")
			(effects
				(font
					(size 0.7874 0.5842)
					(thickness 0.1524)
				)
			)
		)
		(property "Value" ""
			(at 0 0 270)
			(layer "F.Fab")
			(effects
				(font
					(size 1.27 1.27)
				)
			)
		)
		(duplicate_pad_numbers_are_jumpers no)
		(fp_line
			(start -2.286 7.366)
			(end -1.60147 7.366)
			(stroke
				(width 0.1524)
				(type default)
			)
			(layer "F.SilkS")
		)
		(fp_line
			(start -2.286 7.366)
			(end -2.286 1.632712)
			(stroke
				(width 0.1524)
				(type default)
			)
			(layer "F.SilkS")
		)
		(fp_line
			(start 2.286 7.366)
			(end 1.600708 7.366)
			(stroke
				(width 0.1524)
				(type default)
			)
			(layer "F.SilkS")
		)
		(fp_line
			(start 2.286 7.366)
			(end 2.286 1.63195)
			(stroke
				(width 0.1524)
				(type default)
			)
			(layer "F.SilkS")
		)
		(fp_line
			(start -2.563114 1.633728)
			(end -1.6002 1.633728)
			(stroke
				(width 0.1524)
				(type default)
			)
			(layer "F.SilkS")
		)
		(fp_line
			(start 2.504948 1.633728)
			(end 1.6002 1.633728)
			(stroke
				(width 0.1524)
				(type default)
			)
			(layer "F.SilkS")
		)
		(fp_line
			(start -2.563114 -1.616456)
			(end -2.563114 1.633728)
			(stroke
				(width 0.1524)
				(type default)
			)
			(layer "F.SilkS")
		)
		(fp_line
			(start -1.6002 -1.616456)
			(end -2.563114 -1.616456)
			(stroke
				(width 0.1524)
				(type default)
			)
			(layer "F.SilkS")
		)
		(fp_line
			(start 1.6002 -1.616456)
			(end 2.504948 -1.616456)
			(stroke
				(width 0.1524)
				(type default)
			)
			(layer "F.SilkS")
		)
		(fp_line
			(start 2.504948 -1.616456)
			(end 2.504948 1.633728)
			(stroke
				(width 0.1524)
				(type default)
			)
			(layer "F.SilkS")
		)
		(fp_rect
			(start -2.286 7.366)
			(end 2.286 -0.254)
			(stroke
				(width 0)
				(type default)
			)
			(fill no)
			(layer "F.CrtYd")
		)
		(fp_line
			(start -2.286 7.366)
			(end -2.286 -0.254)
			(stroke
				(width 0.1)
				(type default)
			)
			(layer "F.Fab")
		)
		(fp_line
			(start 2.286 7.366)
			(end -2.286 7.366)
			(stroke
				(width 0.1)
				(type default)
			)
			(layer "F.Fab")
		)
		(fp_line
			(start -2.286 -0.254)
			(end 2.286 -0.254)
			(stroke
				(width 0.1)
				(type default)
			)
			(layer "F.Fab")
		)
		(fp_line
			(start 2.286 -0.254)
			(end 2.286 7.366)
			(stroke
				(width 0.1)
				(type default)
			)
			(layer "F.Fab")
		)
		(pad "1" smd rect
			(at 0 0 270)
			(size 2.54 3.048)
			(layers "F.Cu" "F.Mask" "F.Paste")
			(net "P12V_STBY")
		)
		(pad "2" smd rect
			(at 0 7.112 270)
			(size 2.54 3.048)
			(layers "F.Cu" "F.Mask" "F.Paste")
			(net "GND")
		)
	)
)
